# S9S_MB_2U (Grand Teton) — schematic netlist excerpt (pin names and nets, part order shuffled) for the footprints in the layout excerpt that follows; sources: Cadence DE-HDL packaged netlist, KiCad conversion of 03242023_DA0F0TMBIJ0_F0T_Motherboard_J_brd_V01_OCP.brd

C687  Q_CAP_DIFFBUS  DIFF BUS_0.22UF 6.3V 20% X6S  pkg C0201  page 177 : \1\ = P5E_CPU1_PE4_TX_C_DP<11> ; \2\ = P5E_CPU1_PE4_TX_DP<11>
R4805  Q_RES  1K 1% EMPTY  pkg 0402LF  page 306 : A = P3V3_AUX ; B = U369_VDD
C688  Q_CAP_DIFFBUS  DIFF BUS_0.22UF 6.3V 20% X6S  pkg C0201  page 177 : \1\ = P5E_CPU1_PE4_TX_C_DN<10> ; \2\ = P5E_CPU1_PE4_TX_DN<10>

(kicad_pcb
	(version 20260206)
	(generator "pcbnew")
	(generator_version "10.0")
	(general
		(thickness 1.6)
		(legacy_teardrops no)
	)
	(paper "A4")
	(title_block
		(title "03242023_DA0F0TMBIJ0_F0T_Motherboard_J_brd_V01_OCP.brd")
		(comment 1 "Grand Teton / footprints 2757-2759 of 6105")
	)
	(layers
		(0 "F.Cu" signal "TOP")
		(4 "In1.Cu" signal "GND")
		(6 "In2.Cu" signal "IN1")
		(8 "In3.Cu" signal "GND1")
		(10 "In4.Cu" signal "IN2")
		(12 "In5.Cu" signal "GND2")
		(14 "In6.Cu" signal "IN3")
		(16 "In7.Cu" signal "GND3")
		(18 "In8.Cu" signal "VCC")
		(20 "In9.Cu" signal "VCC1")
		(22 "In10.Cu" signal "GND4")
		(24 "In11.Cu" signal "IN4")
		(26 "In12.Cu" signal "GND5")
		(28 "In13.Cu" signal "IN5")
		(30 "In14.Cu" signal "GND6")
		(32 "In15.Cu" signal "IN6")
		(34 "In16.Cu" signal "GND7")
		(2 "B.Cu" signal "BOTTOM")
		(9 "F.Adhes" user "F.Adhesive")
		(11 "B.Adhes" user "B.Adhesive")
		(13 "F.Paste" user "Package Geometry/Pastemask Top")
		(15 "B.Paste" user "Package Geometry/Pastemask Bottom")
		(5 "F.SilkS" user "Ref Des/Silkscreen Top")
		(7 "B.SilkS" user "Ref Des/Silkscreen Bottom")
		(1 "F.Mask" user "Board Geometry/Soldermask Top")
		(3 "B.Mask" user "Board Geometry/Soldermask Bottom")
		(17 "Dwgs.User" user "User.Drawings")
		(19 "Cmts.User" user "User.Comments")
		(21 "Eco1.User" user "User.Eco1")
		(23 "Eco2.User" user "User.Eco2")
		(25 "Edge.Cuts" user "Board Geometry/Outline")
		(27 "Margin" user)
		(31 "F.CrtYd" user "Package Geometry/Place Bound Top")
		(29 "B.CrtYd" user "Package Geometry/Place Bound Bottom")
		(35 "F.Fab" user "Ref Des/Assembly Top")
		(33 "B.Fab" user "Ref Des/Assembly Bottom")
	)
	(footprint ""
		(layer "F.Cu")
		(at 279.0317 -424.69562)
		(property "Reference" "R4805"
			(at 0 0 0)
			(layer "F.SilkS")
			(hide yes)
			(effects
				(font
					(size 1.27 1.27)
				)
			)
		)
		(property "Value" ""
			(at 0 0 0)
			(layer "F.Fab")
			(effects
				(font
					(size 1.27 1.27)
				)
			)
		)
		(duplicate_pad_numbers_are_jumpers no)
		(fp_line
			(start -0.7874 -0.4064)
			(end 0.7874 -0.4064)
			(stroke
				(width 0.1524)
				(type default)
			)
			(layer "F.SilkS")
		)
		(fp_line
			(start -0.7874 0.4064)
			(end -0.7874 -0.4064)
			(stroke
				(width 0.1524)
				(type default)
			)
			(layer "F.SilkS")
		)
		(fp_line
			(start 0.7874 -0.4064)
			(end 0.7874 0.4064)
			(stroke
				(width 0.1524)
				(type default)
			)
			(layer "F.SilkS")
		)
		(fp_line
			(start 0.7874 0.4064)
			(end -0.7874 0.4064)
			(stroke
				(width 0.1524)
				(type default)
			)
			(layer "F.SilkS")
		)
		(fp_line
			(start -0.67945 -0.305054)
			(end -0.12065 -0.305054)
			(stroke
				(width 0.1)
				(type default)
			)
			(layer "F.Fab")
		)
		(fp_line
			(start -0.67945 0.3048)
			(end -0.67945 -0.305054)
			(stroke
				(width 0.1)
				(type default)
			)
			(layer "F.Fab")
		)
		(fp_line
			(start -0.12065 -0.305054)
			(end -0.12065 -0.2794)
			(stroke
				(width 0.1)
				(type default)
			)
			(layer "F.Fab")
		)
		(fp_line
			(start -0.12065 -0.2794)
			(end 0.12065 -0.2794)
			(stroke
				(width 0.1)
				(type default)
			)
			(layer "F.Fab")
		)
		(fp_line
			(start -0.12065 0.2794)
			(end -0.12065 0.3048)
			(stroke
				(width 0.1)
				(type default)
			)
			(layer "F.Fab")
		)
		(fp_line
			(start -0.12065 0.3048)
			(end -0.67945 0.3048)
			(stroke
				(width 0.1)
				(type default)
			)
			(layer "F.Fab")
		)
		(fp_line
			(start 0.120396 0.2794)
			(end -0.12065 0.2794)
			(stroke
				(width 0.1)
				(type default)
			)
			(layer "F.Fab")
		)
		(fp_line
			(start 0.120396 0.3048)
			(end 0.120396 0.2794)
			(stroke
				(width 0.1)
				(type default)
			)
			(layer "F.Fab")
		)
		(fp_line
			(start 0.12065 -0.3048)
			(end 0.67945 -0.3048)
			(stroke
				(width 0.1)
				(type default)
			)
			(layer "F.Fab")
		)
		(fp_line
			(start 0.12065 -0.2794)
			(end 0.12065 -0.3048)
			(stroke
				(width 0.1)
				(type default)
			)
			(layer "F.Fab")
		)
		(fp_line
			(start 0.67945 -0.3048)
			(end 0.67945 0.3048)
			(stroke
				(width 0.1)
				(type default)
			)
			(layer "F.Fab")
		)
		(fp_line
			(start 0.67945 0.3048)
			(end 0.120396 0.3048)
			(stroke
				(width 0.1)
				(type default)
			)
			(layer "F.Fab")
		)
		(pad "1" smd circle
			(at -0.40005 0)
			(size 0 0)
			(layers "F.Cu" "F.Mask" "F.Paste")
			(net "P3V3_AUX")
		)
		(pad "2" smd circle
			(at 0.40005 0)
			(size 0 0)
			(layers "F.Cu" "F.Mask" "F.Paste")
			(net "U369_VDD")
		)
	)
	(footprint ""
		(layer "F.Cu")
		(at 79.933038 -408.517344 -90)
		(property "Reference" "C688"
			(at 0 0 270)
			(layer "F.SilkS")
			(hide yes)
			(effects
				(font
					(size 1.27 1.27)
				)
			)
		)
		(property "Value" ""
			(at 0 0 270)
			(layer "F.Fab")
			(effects
				(font
					(size 1.27 1.27)
				)
			)
		)
		(duplicate_pad_numbers_are_jumpers no)
		(fp_line
			(start -0.299974 0.150114)
			(end -0.299974 -0.150114)
			(stroke
				(width 0.1)
				(type default)
			)
			(layer "F.Fab")
		)
		(fp_line
			(start 0.299974 0.150114)
			(end -0.299974 0.150114)
			(stroke
				(width 0.1)
				(type default)
			)
			(layer "F.Fab")
		)
		(fp_line
			(start -0.299974 -0.150114)
			(end 0.299974 -0.150114)
			(stroke
				(width 0.1)
				(type default)
			)
			(layer "F.Fab")
		)
		(fp_line
			(start 0.299974 -0.150114)
			(end 0.299974 0.150114)
			(stroke
				(width 0.1)
				(type default)
			)
			(layer "F.Fab")
		)
		(pad "1" smd rect
			(at -0.2667 0 270)
			(size 0.3048 0.381)
			(layers "F.Cu" "F.Mask" "F.Paste")
			(net "P5E_CPU1_PE4_TX_C_DN<10>")
		)
		(pad "2" smd rect
			(at 0.2667 0 270)
			(size 0.3048 0.381)
			(layers "F.Cu" "F.Mask" "F.Paste")
			(net "P5E_CPU1_PE4_TX_DN<10>")
		)
	)
	(footprint ""
		(layer "F.Cu")
		(at 82.996278 -408.517344 -90)
		(property "Reference" "C687"
			(at 0 0 270)
			(layer "F.SilkS")
			(hide yes)
			(effects
				(font
					(size 1.27 1.27)
				)
			)
		)
		(property "Value" ""
			(at 0 0 270)
			(layer "F.Fab")
			(effects
				(font
					(size 1.27 1.27)
				)
			)
		)
		(duplicate_pad_numbers_are_jumpers no)
		(fp_line
			(start -0.299974 0.150114)
			(end -0.299974 -0.150114)
			(stroke
				(width 0.1)
				(type default)
			)
			(layer "F.Fab")
		)
		(fp_line
			(start 0.299974 0.150114)
			(end -0.299974 0.150114)
			(stroke
				(width 0.1)
				(type default)
			)
			(layer "F.Fab")
		)
		(fp_line
			(start -0.299974 -0.150114)
			(end 0.299974 -0.150114)
			(stroke
				(width 0.1)
				(type default)
			)
			(layer "F.Fab")
		)
		(fp_line
			(start 0.299974 -0.150114)
			(end 0.299974 0.150114)
			(stroke
				(width 0.1)
				(type default)
			)
			(layer "F.Fab")
		)
		(pad "1" smd rect
			(at -0.2667 0 270)
			(size 0.3048 0.381)
			(layers "F.Cu" "F.Mask" "F.Paste")
			(net "P5E_CPU1_PE4_TX_C_DP<11>")
		)
		(pad "2" smd rect
			(at 0.2667 0 270)
			(size 0.3048 0.381)
			(layers "F.Cu" "F.Mask" "F.Paste")
			(net "P5E_CPU1_PE4_TX_DP<11>")
		)
	)
)
